# BASEBOARD_FAB2 (Tioga Pass) — schematic netlist excerpt (pin names and nets, part order shuffled) for the footprints in the layout excerpt that follows; sources: Cadence DE-HDL packaged netlist, KiCad conversion of Wiwynn_Tioga_Pass_MB.brd

C2U18  CAP  0.22UF 16V 10% X7R  pkg 0402  page 107 : A = P3E_CPU0_PE1_PCH_RXN<7> ; B = P3E_CPU0_PE1_SS_RXN<7>

Q12W4  BSL308C-H6327-GP  pkg DISCRET-GB1  page 197
  \gate#1\  = PWRGD_PVDDQ_KLM
  \source#2\  = P12V_NVDIMM_KLM
  \gate#3\  = PWRGD_PVDDQ_KLM_N
  \drain#4\  = P12V_NVDIMM_KLM_D
  \source#5\  = GND
  \drain#6\  = PWRGD_PVDDQ_KLM_N

(kicad_pcb
	(version 20260206)
	(generator "pcbnew")
	(generator_version "10.0")
	(general
		(thickness 1.6)
		(legacy_teardrops no)
	)
	(paper "A4")
	(title_block
		(title "Wiwynn_Tioga_Pass_MB.brd")
		(comment 1 "Tioga Pass / footprints 4262-4263 of 4770")
	)
	(layers
		(0 "F.Cu" signal "TOP")
		(4 "In1.Cu" signal "L2GND")
		(6 "In2.Cu" signal "L3")
		(8 "In3.Cu" signal "L4GND")
		(10 "In4.Cu" signal "L5")
		(12 "In5.Cu" signal "L6GND")
		(14 "In6.Cu" signal "L7VCC")
		(16 "In7.Cu" signal "L8VCC")
		(18 "In8.Cu" signal "L9GND")
		(20 "In9.Cu" signal "L10")
		(22 "In10.Cu" signal "L11GND")
		(24 "In11.Cu" signal "L12")
		(26 "In12.Cu" signal "L13GND")
		(2 "B.Cu" signal "BOTTOM")
		(9 "F.Adhes" user "F.Adhesive")
		(11 "B.Adhes" user "B.Adhesive")
		(13 "F.Paste" user "Package Geometry/Pastemask Top")
		(15 "B.Paste" user "Package Geometry/Pastemask Bottom")
		(5 "F.SilkS" user "Ref Des/Silkscreen Top")
		(7 "B.SilkS" user "Ref Des/Silkscreen Bottom")
		(1 "F.Mask" user "Board Geometry/Soldermask Top")
		(3 "B.Mask" user "Board Geometry/Soldermask Bottom")
		(17 "Dwgs.User" user "User.Drawings")
		(19 "Cmts.User" user "User.Comments")
		(21 "Eco1.User" user "User.Eco1")
		(23 "Eco2.User" user "User.Eco2")
		(25 "Edge.Cuts" user "Board Geometry/Outline")
		(27 "Margin" user)
		(31 "F.CrtYd" user "Package Geometry/Place Bound Top")
		(29 "B.CrtYd" user "Package Geometry/Place Bound Bottom")
		(35 "F.Fab" user "Ref Des/Assembly Top")
		(33 "B.Fab" user "Ref Des/Assembly Bottom")
	)
	(footprint ""
		(layer "B.Cu")
		(at 354.301806 -61.257434)
		(property "Reference" "C2U18"
			(at 0 0 0)
			(layer "B.SilkS")
			(hide yes)
			(effects
				(font
					(size 1.27 1.27)
				)
				(justify mirror)
			)
		)
		(property "Value" ""
			(at 0 0 0)
			(layer "B.Fab")
			(effects
				(font
					(size 1.27 1.27)
				)
				(justify mirror)
			)
		)
		(duplicate_pad_numbers_are_jumpers no)
		(fp_poly
			(pts
				(xy -0.3048 -0.1016) (xy -0.3048 0.9906) (xy 0.3048 0.9906) (xy 0.3048 -0.1016)
			)
			(stroke
				(width 0)
				(type default)
			)
			(fill no)
			(layer "B.CrtYd")
		)
		(fp_line
			(start -0.3048 -0.1016)
			(end 0.3048 -0.1016)
			(stroke
				(width 0.1)
				(type default)
			)
			(layer "B.Fab")
		)
		(fp_line
			(start -0.3048 0.9906)
			(end -0.3048 -0.1016)
			(stroke
				(width 0.1)
				(type default)
			)
			(layer "B.Fab")
		)
		(fp_line
			(start 0.3048 -0.1016)
			(end 0.3048 0.9906)
			(stroke
				(width 0.1)
				(type default)
			)
			(layer "B.Fab")
		)
		(fp_line
			(start 0.3048 0.9906)
			(end -0.3048 0.9906)
			(stroke
				(width 0.1)
				(type default)
			)
			(layer "B.Fab")
		)
		(pad "1" smd rect
			(at 0 0 180)
			(size 0.508 0.508)
			(layers "B.Cu" "B.Mask" "B.Paste")
			(net "P3E_CPU0_PE1_PCH_RXN<7>")
		)
		(pad "2" smd rect
			(at 0 0.889 180)
			(size 0.508 0.508)
			(layers "B.Cu" "B.Mask" "B.Paste")
			(net "P3E_CPU0_PE1_SS_RXN<7>")
		)
		(zone
			(layer "B.Cu")
			(hatch none 0.5)
			(connect_pads
				(clearance 0)
			)
			(min_thickness 0.25)
			(keepout
				(tracks allowed)
				(vias not_allowed)
				(pads allowed)
				(copperpour not_allowed)
				(footprints allowed)
			)
			(placement
				(enabled no)
				(sheetname "")
			)
			(fill
				(thermal_gap 0.5)
				(thermal_bridge_width 0.5)
				(island_removal_mode 0)
			)
			(polygon
				(pts
					(xy 354.555806 -61.003434) (xy 354.047806 -61.003434) (xy 354.047806 -60.622434) (xy 354.555806 -60.622434)
				)
			)
		)
		(zone
			(layer "B.Cu")
			(hatch none 0.5)
			(connect_pads
				(clearance 0)
			)
			(min_thickness 0.25)
			(keepout
				(tracks not_allowed)
				(vias allowed)
				(pads allowed)
				(copperpour not_allowed)
				(footprints allowed)
			)
			(placement
				(enabled no)
				(sheetname "")
			)
			(fill
				(thermal_gap 0.5)
				(thermal_bridge_width 0.5)
				(island_removal_mode 0)
			)
			(polygon
				(pts
					(xy 354.555806 -60.622434) (xy 354.047806 -60.622434) (xy 354.047806 -61.003434) (xy 354.555806 -61.003434)
				)
			)
		)
	)
	(footprint ""
		(layer "B.Cu")
		(at 10.2108 -124.9172)
		(property "Reference" "Q12W4"
			(at 0 0 0)
			(layer "B.SilkS")
			(hide yes)
			(effects
				(font
					(size 1.27 1.27)
				)
				(justify mirror)
			)
		)
		(property "Value" "*"
			(at 4.572 -7.6835 0)
			(unlocked yes)
			(layer "B.Fab")
			(hide yes)
			(effects
				(font
					(size 1.27 1.016)
					(thickness 0.1524)
				)
				(justify mirror)
			)
		)
		(property "Device Type" "BSL308C-H6327-GP_DISCRET-GB1-BA"
			(at 4.572 -9.2075 0)
			(unlocked yes)
			(layer "B.Fab")
			(hide yes)
			(effects
				(font
					(size 1.27 1.016)
					(thickness 0.1524)
				)
				(justify mirror)
			)
		)
		(duplicate_pad_numbers_are_jumpers no)
		(fp_line
			(start -1.102868 -0.081534)
			(end -1.102868 0.081534)
			(stroke
				(width 0.1524)
				(type default)
			)
			(layer "B.SilkS")
		)
		(fp_line
			(start -1.102868 0.081534)
			(end 1.8796 0.081534)
			(stroke
				(width 0.1524)
				(type default)
			)
			(layer "B.SilkS")
		)
		(fp_line
			(start 1.524 0)
			(end 1.8796 0.081534)
			(stroke
				(width 0.1524)
				(type default)
			)
			(layer "B.SilkS")
		)
		(fp_line
			(start 1.7018 0.3048)
			(end 1.7018 1.8796)
			(stroke
				(width 0.508)
				(type default)
			)
			(layer "B.SilkS")
		)
		(fp_line
			(start 1.8796 -0.081534)
			(end -1.102868 -0.081534)
			(stroke
				(width 0.1524)
				(type default)
			)
			(layer "B.SilkS")
		)
		(fp_line
			(start 1.8796 -0.081534)
			(end 1.524 0)
			(stroke
				(width 0.1524)
				(type default)
			)
			(layer "B.SilkS")
		)
		(fp_line
			(start 1.8796 0.081534)
			(end 1.8796 -0.081534)
			(stroke
				(width 0.1524)
				(type default)
			)
			(layer "B.SilkS")
		)
		(fp_poly
			(pts
				(xy 1.179068 0.081534) (xy 1.179068 -0.081534) (xy -1.102868 -0.081534) (xy -1.102868 0.081534)
			)
			(stroke
				(width 0)
				(type default)
			)
			(fill yes)
			(layer "B.SilkS")
		)
		(fp_rect
			(start 1.4478 1.2446)
			(end -1.4478 -1.2446)
			(stroke
				(width 0)
				(type default)
			)
			(fill no)
			(layer "B.CrtYd")
		)
		(fp_poly
			(pts
				(xy 1.4478 -1.23952) (xy 1.9558 -1.23952) (xy 1.9558 2.1336) (xy -1.9558 2.1336) (xy -1.9558 -2.1336)
				(xy 1.9558 -2.1336) (xy 1.9558 -1.2446) (xy -1.4478 -1.2446) (xy -1.4478 1.2446) (xy 1.4478 1.2446)
			)
			(stroke
				(width 0)
				(type default)
			)
			(fill no)
			(layer "B.CrtYd")
		)
		(fp_rect
			(start 1.9558 2.1336)
			(end -1.9558 -2.1336)
			(stroke
				(width 0)
				(type default)
			)
			(fill no)
			(layer "B.Fab")
		)
		(pad "1" smd rect
			(at 0.950468 0.995934 180)
			(size 0.4572 1.27)
			(layers "B.Cu" "B.Mask" "B.Paste")
			(net "PWRGD_PVDDQ_KLM")
		)
		(pad "2" smd rect
			(at 0 0.995934 180)
			(size 0.4572 1.27)
			(layers "B.Cu" "B.Mask" "B.Paste")
			(net "P12V_NVDIMM_KLM")
		)
		(pad "3" smd rect
			(at -0.950468 0.995934 180)
			(size 0.4572 1.27)
			(layers "B.Cu" "B.Mask" "B.Paste")
			(net "PWRGD_PVDDQ_KLM_N")
		)
		(pad "4" smd rect
			(at -0.950468 -0.995934 180)
			(size 0.4572 1.27)
			(layers "B.Cu" "B.Mask" "B.Paste")
			(net "P12V_NVDIMM_KLM_D")
		)
		(pad "5" smd rect
			(at 0 -0.995934 180)
			(size 0.4572 1.27)
			(layers "B.Cu" "B.Mask" "B.Paste")
			(net "GND")
		)
		(pad "6" smd rect
			(at 0.950468 -0.995934 180)
			(size 0.4572 1.27)
			(layers "B.Cu" "B.Mask" "B.Paste")
			(net "PWRGD_PVDDQ_KLM_N")
		)
	)
)
